# ZAIUS-MB-EVT3-HW-EBOM-X00_20161228-add_2nd_source_X15-20170106-Final.xls — DEPOP (bom)
| FOXCONN TECHNOLOGY GROUP |  |  |  |  |  |  |  |  |  |  |  |  |
| BILL OF MATERIAL |  |  |  |  |  |  |  |  |  |  |  |  |
| REV OF  BOM |  | CUSTOMER | <name> |  | CUSTOMER P/N |  | PRODUCT CODE |  | PWA  REV |  | DATE |  |
| Sourcing (Single/Sole/Multi) | Critical Commodity (Y or N) | Component Class (1, 2, other) | Customer PSL (Y or N) | Item Number | Foxconn P/N | Customer P/N | Part Description | Manufacturer  Full Name | Manufacturer  Part Number | Qty | RoHS Status | Location |
|  |  |  |  | 1 | 62010FF00-015-G |  | CAP,47pF,+/-5%,NPO(C0G),50V,G,SMD0402 | MURATA ELEC. NORTH AMERICA | GRM1555C1H470J | 38 |  | C1,C2,C3,C4,C7,C8,C16,C17,C18,C19,C20,C21,C22,C23,C24,C25,C26,C27,C28,C29,C30,C31,C32,C726,C727,C728,C729,C739,C740,C741,C742,C743,C744,C745,C746,C747,C748,C2180 |
|  |  |  |  | 2 | 620103700-015-G |  | CAP,100nF,+/-10%,X7R,10V,G,SMD0402 | MURATA ELEC. NORTH AMERICA | GRM155R71A104K | 4 |  | C37,C204,C205,C753 |
|  |  |  |  | 3 | 62012WD00-015-G |  | CAP,4.7uF,+/-20%,X6S,6.3V,G,SMD0402 | MURATA ELEC. NORTH AMERICA | GRM155C80J475MEAAD | 2 |  | C60,C757 |
|  |  |  |  | 4 | 62011DF01-015-G |  | CAP,220nF,+/-10%,X7R,16V,G,SMD0402 | MURATA ELEC. NORTH AMERICA | GRM155R71C224K | 8 |  | C80,C83,C138,C794,C795,C814,C897,C904 |
|  |  |  |  | 5 | 620107G00-015-G |  | CAP,47nF,+/-10%,X7R,16V,G,SMD0402 | MURATA ELEC. NORTH AMERICA | GRM155R71C473K | 3 |  | C184,C231,C232 |
|  |  |  |  | 6 | 62012NU00-015-G |  | CAP,1uF,+/-10%,X7R,6.3V,G,SMD0402 | MURATA ELEC. NORTH AMERICA | GRM155R70J105KA12D | 1 |  | C202 |
|  |  |  |  | 7 | 62012PS00-015-G |  | CAP,10uF,+/-20%,X6S,4V,G,SMD0402 | MURATA ELEC. NORTH AMERICA | GRM155C80G106M | 10 |  | PBFC61,PBEC61,PAFC61,PAEC61,PBMC62,PAMC62,PBAC126,PAAC126,C264,C2171 |
|  |  |  |  | 8 | 62011U701-015-G |  | CAP,10nF,+/-10%,X7R,6.3V,G,SMD0402 | MURATA ELEC. NORTH AMERICA | GRM155R70J103K | 1 |  | C1511 |
|  |  |  |  | 9 | 62010BJ00-015-G |  | CAP,56pF,+/-5%,NPO(C0G),50V,G,SMD0402 | MURATA ELEC. NORTH AMERICA | GRM1555C1H560J | 2 |  | C1553,C1558 |
|  |  |  |  | 10 | 62010GW00-015-G |  | CAP,10pF,+/-5%,NPO,50V,G,SMD0402 | MURATA ELEC. NORTH AMERICA | GRM1555C1H100J | 26 |  | PBMC7,PBFC7,PBEC7,PBAC7,PAMC7,PAFC7,PAEC7,PAAC7,PBMC8,PBFC8,PBEC8,PBAC8,PAMC8,PAFC8,PAEC8,PAAC8,PBMC9,PBFC9,PBEC9,PBAC9,PAMC9,PAFC9,PAEC9,PAAC9,C1556,C1557 |
|  |  |  |  | 11 | 62010QB00-015-G |  | CAP,10nF,+/-10%,X7R,50V,G,SMD0402 | MURATA ELEC. NORTH AMERICA | GRM155R71H103K | 11 |  | PSRC1,PSTC9,PSLC9,PSFC9,PSEC9,PSDC9,PQPC9,PFRC9,PEEC9,PEDC9,C2071 |
|  |  |  |  | 12 | 520305M00-223-G |  | DIODE,Schottky Rectifier,MBRS340T3G,40V,3A,G,SMC,SMD | ON SEMICONDUCTOR CORP | MBRS340T3G | 8 |  | D1,D2,D3,D4,D5,D6,D7,D51 |
|  |  |  |  | 13 | 520306F00-223-G |  | DIODE,Schottky,NSR0320MW2T1G,20V,1A,G,SOD323-2,SMD | ON SEMICONDUCTOR CORP | NSR0320MW2T1G | 1 |  | D52 |
|  |  |  |  | 14 | 62011J601-015-G |  | CAP,2.2uF,+/-10%,X7R,100V,G,SMD1210 | MURATA ELEC. NORTH AMERICA | GRM32ER72A225K | 8 |  | PBMC20,PBFC20,PBAC20,PAMC20,PAEC20,PBEC21,PAFC21,PAAC21 |
|  |  |  |  | 15 | 62012GY00-015-G |  | CAP,100nF,+/-20%,X7R,25V,G,SMD0402 | MURATA ELEC. NORTH AMERICA | GRM155R71E104M | 16 |  | PBMC23,PBFC23,PBEC23,PAMC23,PAFC23,PAEC23,PBMC24,PBFC24,PBEC24,PBAC24,PAMC24,PAFC24,PAEC24,PAAC24,PBAC25,PAAC25 |
|  |  |  |  | 16 | 62011DA00-015-G |  | CAP,1uF,+/-10%,X7R,100V,G,SMD1206 | MURATA ELEC. NORTH AMERICA | GRM31CR72A105K | 10 |  | PBMC28,PBAC28,PAMC28,PAAC28,PBAC79,PAAC79,PBAC80,PAAC80,PBAC112,PAAC112 |
|  |  |  |  | 17 | 62010VD00-015-G |  | CAP,100nF,+/-10%,X7R,100V,G,SMD0603 | MURATA ELEC. NORTH AMERICA | GRM188R72A104K | 16 |  | PBMC401,PBFC401,PBEC401,PBAC401,PAMC401,PAFC401,PAEC401,PAAC401,PBMC402,PBFC402,PBEC402,PBAC402,PAMC402,PAFC402,PAEC402,PAAC402 |
|  |  |  |  | 18 | 62012RJ00-015-G |  | CAP,4.7uF,+/-10%,X6S,16V,G,SMD0603 | MURATA ELEC. NORTH AMERICA | GRM188C81C475K | 2 |  | PBAC451,PAAC451 |
|  |  |  |  | 19 | 52030W700-237-G |  | DIODE,Schottky,BAT54WT-7,30V,100mA,G,SOD523-2,SMD | DIODES INEORPORATION | BAT54WT-7 | 8 |  | PBMD2,PBFD2,PBED2,PBAD2,PAMD2,PAFD2,PAED2,PAAD2 |
|  |  |  |  | 20 | 520300600-237-G |  | DIODE,Schottky,BAT54A-7-F,30V,0.2A,G,SOT23-3,SMD | DIODES INEORPORATION | BAT54A-7-F | 2 |  | PBAD4,PAAD4 |
|  |  |  |  | 21 | 63035NQ00-029-G |  | IND,0.1uH@100KHz,+/-20%,11.5A,6mOhm,SHLD,G,SMD | VISHAY ENTER TECHNO LOGY.INC | IHLP1616ABERR10M01 | 2 |  | PBAL4,PAAL4 |
|  |  |  |  | 22 | 610107A00-017-G |  | RES,0 Ohm,+/-5%,1/16W,G,SMD0402 | KOA SPEER ELECTRONICS, INC. | RK73Z1ETTP | 303 |  | R909,R921,PSRR5,PBFR5,PBER5,PBAR5,PAFR5,PAER5,PAAR5,PBFR6,PBER6,PAFR6,PAER6,PAAR6,PBMR7,PBAR7,PAFR7,PSTR8,PSER8,PBFR8,PBER8,PAAR8,PAER9,PHAR10,PBAR10,PAMR10,PBFR11,PAAR11,PBMR12,PBER12,PAER12,PSTR13,PSLR13,PSFR13,PSER13,PSDR13,PQPR13,PFRR13,PEER13,PEDR13,PBAR13,PAFR13,PAER13,PBAR14,PAMR15,PHAR16,PBFR16,PBER16,PAFR16,PAAR16,PSPR17,PIPR17,PHAR17,PFPR17,PEPR17,PHAR18,PBMR19,PBFR19,PBER19,PBAR19,PAMR19,PAFR19,PAER19,PAAR19,PBMR20,PBFR20,PBER20,PBAR20,PAMR20,PAFR20,PAER20,PAAR20,PHAR21,PBMR23,PBFR23,PBER23,PBAR23,PAMR23,PAFR23,PAER23,PAAR23,PSRR24,PHAR26,PHAR27,PBNR28,PANR28,PBMR29,PBFR29,PBER29,PBAR29,PAMR29,PAFR29,PAER29,PAAR29,PBMR31,PBFR31,PBER31,PBAR31,PAMR31,PAFR31,PAER31,PAAR31,PHAR37,PBMR37,PBFR37,PBER37,PBAR37,PAMR37,PAFR37,PAER37,PAAR37,PBMR73,PAMR73,PBER76,PBAR76,PAFR76,PAER76,PAAR76,PBFR77,PBMR80,PAMR80,PBAR82,PAFR82,PAAR82,PBMR83,PBFR83,PBAR83,PAMR83,PAAR83,PBMR84,PAMR84,PBER86,PAFR86,PAER86,PBFR87,PBAR87,PAAR87,PBER88,PBAR88,PAFR88,PAER88,PAAR88,PBFR89,PBAR99,PAAR99,PBMR101,PAMR101,PBER103,PAFR103,PAER103,PBFR104,PBMR105,PAMR105,PBMR106,PAMR106,PBER107,PBAR107,PAFR107,PAER107,PAAR107,PBMR108,PBFR108,PBER108,PAMR108,PAFR108,PAER108,PBFR109,PBER110,PAFR110,PAER110,PBFR111,PBAR111,PAAR111,PBMR112,PBAR112,PAMR112,PAAR112,PBMR114,PBER114,PBAR114,PAMR114,PAFR114,PAER114,PAAR114,PBFR115,PBER116,PAFR116,PAER116,PBFR117,PBAR118,PAAR118,PBMR119,PAMR119,PBMR120,PBAR120,PAMR120,PAAR120,PBER121,PAFR121,PAER121,PBFR122,PBER122,PAFR122,PAER122,PBFR123,PBAR125,PAAR125,PBAR126,PAAR126,PBFR304,PBER304,PAFR304,PAER304,PBFR308,PAFR308,PAER308,PBFR309,PBER309,PAFR309,PAER309,PBMR310,PBER310,PBAR310,PAMR310,PAAR310,PBMR311,PBFR311,PBAR311,PAMR311,PAFR311,PAER311,PAAR311,PBMR312,PBER312,PBAR312,PAMR312,PAAR312,PBMR450,PBFR450,PBER450,PBAR450,PAMR450,PAFR450,PAER450,PAAR450,PAAR451,PBAR452,PAAR452,PBAR454,PBMR610,PBAR610,PAMR610,PAAR610,PBAR611,PAAR611,PBAR612,PAAR612,PAFR635,R653,R654,R655,R656,R659,PBFR660,PBER660,PAER685,R752,R803,R819,R821,R948,R1071,R1087,R1101,R1103,R1107,R1120,R1121,R1122,R1123,R1124,R1142,R1144,R1230,R1287,R1452,R1453,R1454,R1455,R1456,R1457,R1458,R1459,R1479,R1486,R1489,R1529,R1530,PSRR3004,PEPR3008,PIPR3009,PFPR3009,PSPR3014 |
|  |  |  |  | 23 | 61010PS00-017-G |  | RES,200KOhm,+/-1%,1/16W,G,SMD0402 | KOA SPEER ELECTRONICS, INC. | RK73H1ETTP2003F | 6 |  | PBAR8,PBFR9,PAAR9,PBER10,PAFR12,PAER14 |
|  |  |  |  | 24 | 61010G500-017-G |  | RES,10KOhm,+/-1%,1/16W,G,SMD0402 | KOA SPEER ELECTRONICS, INC. | RK73H1ETTP1002F | 54 |  | PHAR3,PBMR51,PBFR51,PBER51,PBAR51,PAMR51,PAFR51,PAER51,PAAR51,PBMR52,PBFR52,PBER52,PBAR52,PAMR52,PAFR52,PAER52,PAAR52,PBMR53,PBFR53,PBER53,PBAR53,PAMR53,PAFR53,PAER53,PAAR53,PBMR71,PAMR71,PBMR72,PAMR72,PBER73,PBAR73,PAFR73,PAER73,PAAR73,PBFR74,PBER75,PBAR75,PAFR75,PAER75,PAAR75,PBFR76,R903,R904,R907,R908,R910,R953,R1013,R1014,R1415,R1790,PSRR3007,R905,R915 |
|  |  |  |  | 25 | 610130Y00-017-G |  | RES,1 Ohm,+/-1%,1/3W,G,SMD1206 | KOA SPEER ELECTRONICS, INC. | SR732BTTD1R00F | 10 |  | PBMR60,PBAR60,PAMR60,PAAR60,PBER63,PAFR63,PAER63,PBFR64,PBAR100,PAAR100 |
|  |  |  |  | 26 | 610108300-017-G |  | RES,0 Ohm,+/-5%,1/10W,G,SMD0603 | KOA SPEER ELECTRONICS, INC. | RK73Z1JTTD | 20 |  | PBNR1,PANR1,PBMR67,PAMR69,PAAR70,PBAR71,PBAR74,PAAR74,PBER80,PAFR80,PAER80,PBFR81,PAER123,PBFR520,PBER520,PAFR520,PBMR609,PBAR609,PAMR609,PAAR609 |
|  |  |  |  | 27 | 61010L100-017-G |  | RES,100KOhm,+/-1%,1/16W,G,SMD0402 | KOA SPEER ELECTRONICS, INC. | RK73H1ETTP1003F | 8 |  | PBFR517,PBER517,PAFR517,PAER518,PBMR602,PBAR602,PAMR602,PAAR602 |
|  |  |  |  | 28 | 880302200-53N-G |  | Converter,input 0V~60V,185W,G,VTM48MP012T130AA0 | Vicor Corporation | VTM48MP012T130AA0 | 2 |  | PBAU5,PAAU5 |
|  |  |  |  | 29 | 62120ER01-024-G |  | ECAP,SPEA,470uF,+/-20%,2.5V,105C,G,SMD2816,ESR<=3mOhm | PANASONIC INDUSTRIAL CO.,LTD. | EEFGX0E471R | 8 |  | PBECE7,PAFCE7,PAECE7,PBFCE8,PBECE8,PAFCE8,PAECE8,PBFCE9 |
|  |  |  |  | 30 | 62010L800-015-G |  | CAP,1nF,+/-5%,NPO(C0G),50V,G,SMD0402 | MURATA ELEC. NORTH AMERICA | GRM1555C1H102J | 5 |  | PBFC5,PBEC5,PAFC5,PAEC5,PSRC8 |
|  |  |  |  | 31 | 62012YR00-015-G |  | CAP,470nF,+/-10%,X7R,100V,G,SMD0805 | MURATA ELEC. NORTH AMERICA | GRM21BR72A474KA73L | 4 |  | PBFC27,PBEC27,PAFC27,PAEC27 |
|  |  |  |  | 32 | 610114S00-017-G |  | RES,4.99KOhm,+/-1%,1/16W,G,SMD0402 | KOA SPEER ELECTRONICS, INC. | RK73H1ETTP4991F | 4 |  | PBFR39,PBER39,PAFR39,PAER39 |
|  |  |  |  | 33 | 62012UU00-015-G |  | CAP,100uF,+/-20%,X6S,4V,G,SMD0805 | MURATA ELEC. NORTH AMERICA | GRM21BC80G107ME15L | 2 |  | PBNC24,PANC24 |
|  |  |  |  | 34 | 61010LA00-017-G |  | RES,4.7KOhm,+/-1%,1/16W,G,SMD0402 | KOA SPEER ELECTRONICS, INC. | RK73H1ETTP4701F | 42 |  | PSPR1,PIPR1,PFPR1,PEPR1,PBNR2,PANR2,PSRR6,PBNR9,PANR9,PSPR16,PIPR16,PFPR16,PEPR16,R352,R354,R358,R360,R663,R681,R682,R684,R685,R686,R687,R708,R709,R710,R731,R732,R897,R939,R1001,R1119,R1126,R1153,R1294,R1526,R1533,PSPR3005,PIPR3005,PFPR3005,PEPR3005 |
|  |  |  |  | 35 | 61011G200-017-G |  | RES,12.4KOhm,+/-1%,1/16W,G,SMD0402 | KOA SPEER ELECTRONICS, INC. | RK73H1ETTP1242F | 2 |  | PBNR8,PANR8 |
|  |  |  |  | 36 | 610114A00-017-G |  | RES,24.9KOhm,+/-1%,1/16W,G,SMD0402 | KOA SPEER ELECTRONICS, INC. | RK73H1ETTP2492F | 2 |  | PBNR19,PANR19 |
|  |  |  |  | 37 | 61011CL00-017-G |  | RES,66.5KOhm,+/-1%,1/16W,G,SMD0402 | KOA SPEER ELECTRONICS, INC. | RK73H1ETTP6652F | 2 |  | PBNR25,PANR25 |
|  |  |  |  | 38 | 62010HR00-015-G |  | CAP,100nF,+/-10%,X7R,50V,G,SMD0603 | MURATA ELEC. NORTH AMERICA | GRM188R71H104K | 11 |  | PUAC9,PSIC9,PSAC9,PRAC9,PQAC9,PPAC9,PIAC9,PFAC9,PETC9,PERC9,PEAC9 |
|  |  |  |  | 39 | 620103K00-015-G |  | CAP,1nF,+/-10%,X7R,50V,G,SMD0402 | MURATA ELEC. NORTH AMERICA | GRM155R71H102K | 11 |  | PUAC17,PSIC17,PSAC17,PRAC17,PQAC17,PPAC17,PIAC17,PFAC17,PETC17,PERC17,PEAC17 |
|  |  |  |  | 40 | 620105U00-015-G |  | CAP,220pF,+/-10%,X7R,50V,G,SMD0402 | MURATA ELEC. NORTH AMERICA | GRM155R71H221K | 9 |  | PSTC13,PSLC13,PSFC13,PSEC13,PSDC13,PQPC13,PFRC13,PEEC13,PEDC13 |
|  |  |  |  | 41 | 610112M00-017-G |  | RES,13KOhm,+/-1%,1/16W,G,SMD0402 | KOA SPEER ELECTRONICS, INC. | RK73H1ETTP1302F | 8 |  | PSTR1,PSLR1,PSFR1,PSER1,PSDR1,PQPR1,PEER1,PEDR1 |
|  |  |  |  | 42 | 610114H00-017-G |  | RES,20KOhm,+/-1%,1/16W,G,SMD0402 | KOA SPEER ELECTRONICS, INC. | RK73H1ETTP2002F | 12 |  | PSTR3,PSLR3,PSFR3,PSER3,PSDR3,PQPR3,PEER3,PEDR3,R1757,R1758,R1759,R1760 |
|  |  |  |  | 43 | 61011HA00-017-G |  | RES,1 Ohm,+/-1%,1/16W,G,SMD0402 | KOA SPEER ELECTRONICS, INC. | RK73H1ETTP1R00F | 10 |  | PSTR14,PSLR14,PSFR14,PSER14,PSDR14,PQPR14,PFRR14,PEER14,PEDR14,PSRR19 |
|  |  |  |  | 44 | 620101T02-015-G |  | CAP,100nF,+/-10%,X7R,16V,G,SMD0402 | MURATA ELEC. NORTH AMERICA | GRM155R71C104K | 4 |  | PSPC13,PIPC13,PFPC13,PEPC13 |
|  |  |  |  | 45 | 61011H300-017-G |  | RES,316 Ohm,+/-1%,1/16W,G,SMD0402 | KOA SPEER ELECTRONICS, INC. | RK73H1ETTP3160F | 8 |  | PSPR18,PIPR18,PFPR18,PEPR18,PIPR3008,PFPR3008,PEPR3009,PSPR3015 |
|  |  |  |  | 46 | 61100LR00-017-G |  | RES,100 Ohm,+/-1%,1/16W,G,SMD0402 | KOA SPEER ELECTRONICS, INC. | RN731ETTP1000F50 | 5 |  | PSPR19,PIPR19,PFPR19,PEPR19,R1485 |
|  |  |  |  | 47 | 61100BP00-017-G |  | RES,3.09KOhm,+/-0.1%,1/16W,G,SMD0402 | KOA SPEER ELECTRONICS, INC. | RN731ETTP3091B25 | 4 |  | PSPR3006,PIPR3006,PFPR3006,PEPR3006 |
|  |  |  |  | 48 | 610129400-017-G |  | RES,511KOhm,+/-1%,1/16W,G,SMD0402 | KOA SPEER ELECTRONICS, INC. | RK73H1ETTP5113F | 1 |  | PHAR19 |
|  |  |  |  | 49 | 61100N100-017-G |  | RES,2.37KOhm,+/-0.1%,1/16W,G,SMD0402 | KOA SPEER ELECTRONICS, INC. | RN731ETTP2371B25 | 1 |  | PSRR3 |
|  |  |  |  | 50 | 61100PK00-017-G |  | RES,10.7KOhm,+/-0.1%,1/16W,G,SMD0402 | KOA SPEER ELECTRONICS, INC. | RN731ETTP1072B25 | 1 |  | PSRR4 |
|  |  |  |  | 51 | 61100D400-017-G |  | RES,1.87KOhm,+/-0.1%,1/16W,G,SMD0402 | KOA SPEER ELECTRONICS, INC. | RN731ETTP1871B25 | 1 |  | PSRR10 |
|  |  |  |  | 52 | 610109900-017-G |  | RES,1KOhm,+/-1%,1/10W,G,SMD0603 | KOA SPEER ELECTRONICS, INC. | RK73H1JTTD1001F | 1 |  | PSRR21 |
|  |  |  |  | 53 | 61100PM00-017-G |  | RES,453 Ohm,+/-0.1%,1/16W,G,SMD0402 | KOA SPEER ELECTRONICS, INC. | RN731ETTP4530B25 | 1 |  | PSRR23 |
|  |  |  |  | 54 | 61010L300-017-G |  | RES,1KOhm,+/-1%,1/16W,G,SMD0402 | KOA SPEER ELECTRONICS, INC. | RK73H1ETTP1001F | 5 |  | R14,R15,R377,R378,R1499 |
|  |  |  |  | 55 | 61010FG00-017-G |  | RES,20KOhm,+/-5%,1/16W,G,SMD0402 | KOA SPEER ELECTRONICS, INC. | RK73B1ETTP203J | 5 |  | R60,R61,R62,R63,R64 |
|  |  |  |  | 56 | 61011WQ00-017-G |  | RES,3KOhm,+/-1%,1/16W,G,SMD0402 | KOA SPEER ELECTRONICS, INC. | RK73H1ETTP3001F | 2 |  | R67,R1799 |
|  |  |  |  | 57 | 610102C00-017-G |  | RES,15KOhm,+/-5%,1/16W,G,SMD0402 | KOA SPEER ELECTRONICS, INC. | RK73B1ETTP153J | 2 |  | R77,R1800 |
|  |  |  |  | 58 | 61010KJ00-017-G |  | RES,3.3KOhm,+/-5%,1/16W,G,SMD0402 | KOA SPEER ELECTRONICS, INC. | RK73B1ETTP332J | 22 |  | R90,R443,R1030,R1036,R1037,R1038,R1039,R1040,R1045,R1046,R1049,R1052,R1053,R1056,R1057,R1058,R1061,R1062,R1065,R1066,R1231,R1338 |
|  |  |  |  | 59 | 610102700-017-G |  | RES,49.9 Ohm,+/-1%,1/16W,G,SMD0402 | KOA SPEER ELECTRONICS, INC. | RK73H1ETTP49R9F | 120 |  | R91,R92,R93,R102,R118,R119,R120,R134,R135,R136,R144,R145,R149,R156,R157,R159,R165,R168,R170,R176,R178,R181,R185,R190,R191,R199,R201,R202,R210,R211,R212,R218,R219,R220,R228,R229,R233,R241,R242,R243,R249,R252,R254,R260,R262,R265,R269,R274,R275,R283,R285,R286,R294,R295,R296,R444,R450,R451,R462,R489,R490,R491,R499,R500,R504,R511,R512,R514,R520,R523,R525,R532,R534,R536,R540,R545,R546,R554,R556,R557,R565,R566,R567,R573,R574,R575,R583,R584,R588,R595,R596,R598,R604,R607,R609,R616,R618,R619,R624,R629,R630,R638,R640,R641,R649,R650,R651,R1140,R1279,R1399,R1400,R1403,R1404,R1405,R1791,R1792,R1793,R1794,R1795,R1796 |
|  |  |  |  | 60 | 610107C00-017-G |  | RES,10KOhm,+/-5%,1/16W,G,SMD0402 | KOA SPEER ELECTRONICS, INC. | RK73B1ETTP103J | 3 |  | R116,R305,R471 |
|  |  |  |  | 61 | 61010FL00-017-G |  | RES,2.2KOhm,+/-5%,1/16W,G,SMD0402 | KOA SPEER ELECTRONICS, INC. | RK73B1ETTP222J | 14 |  | R667,R672,R675,R676,R691,R692,R693,R694,R695,R696,R697,R698,R716,R718 |
|  |  |  |  | 62 | 610100T00-017-G |  | RES,1KOhm,+/-5%,1/16W,G,SMD0402 | KOA SPEER ELECTRONICS, INC. | RK73B1ETTP102J | 6 |  | R703,R707,R712,R713,R714,R737 |
|  |  |  |  | 63 | 61011KS00-017-G |  | RES,47KOhm,+/-1%,1/16W,G,SMD0402 | KOA SPEER ELECTRONICS, INC. | RK73H1ETTP4702F | 1 |  | R720 |
|  |  |  |  | 64 | 61011H500-017-G |  | RES,22 Ohm,+/-1%,1/16W,G,SMD0402 | KOA SPEER ELECTRONICS, INC. | RK73H1ETTP22R0F | 1 |  | R721 |
|  |  |  |  | 65 | 61011U901-017-G |  | RES,120Ohm,+/-1%,1/20W,G,SMD0201 | KOA SPEER ELECTRONICS, INC. | RK73H1HTTC1200F | 4 |  | R837,R838,R863,R892 |
|  |  |  |  | 66 | 610107F00-017-G |  | RES,1KOhm,+/-5%,1/10W,G,SMD0603 | KOA SPEER ELECTRONICS, INC. | RK73B1JTTD102J | 3 |  | R1079,R1081,R1778 |
|  |  |  |  | 67 | 611003D00-017-G |  | RES,1KOhm,+/-0.1%,1/16W,G,SMD0402 | KOA SPEER ELECTRONICS, INC. | RN731ETTP1001B25 | 1 |  | R1112 |
|  |  |  |  | 68 | 61011CY00-017-G |  | RES,5.6KOhm,+/-1%,1/16W,G,SMD0402 | KOA SPEER ELECTRONICS, INC. | RK73H1ETTP5601F | 4 |  | R1266,R1270,R1274,R1278 |
|  |  |  |  | 69 | 61100AH00-017-G |  | RES,10KOhm,+/-0.5%,1/16W,G,SMD0402 | KOA SPEER ELECTRONICS, INC. | RN731ETTP1002D25 | 6 |  | R1299,R1300,R1301,R1302,R1306,R1309 |
|  |  |  |  | 70 | 610154700-017-G |  | RES,10KOhm,+/-5%,1/8W,G,SMD0402 | KOA SPEER ELECTRONICS, INC. | SG73P1ETTP103J | 2 |  | R1324,R1326 |
|  |  |  |  | 71 | 61012LR00-017-G |  | RES,1KOhm,+/-0.5%,1/16W,G,SMD0402 | KOA SPEER ELECTRONICS, INC. | RK73H1ETTP1001D | 1 |  | R1481 |
|  |  |  |  | 72 | 410400T00-214-G |  | EEPROM,M93C46-WMN6TP,2.5~5.5V,1K,3-wire serial,G,SO-8,SMD | ST MICRO ELECTRONICS,INC | M93C46-WMN6TP | 1 |  | U39 |
|  |  |  |  | 73 | 34060VU00-309-G |  | CONN,Pin Header,1X2,V/T,Bla,2.54mm,10u,G,SMD-2 | SAMTEC INC. | TSM-102-01-L-SV-P-TR | 3 |  | J104,J117,J125 |
|  |  |  |  | 74 | 3406A9H00-309-G |  | CONN,Header,Socket,V/T,Bla,2.54mm,30u,G,SMD-12 | SAMTEC INC. | SSM-106-S-DV-P-TR | 1 |  | J34 |
|  |  |  |  | 75 | 3406AGV00-317-G |  | CONN,Header,WTB,2X8,V/T,Whi,1.25mm,G,SMD-16 | MOLEX INCORPORATED | 5054331671 | 1 |  | J12 |
|  |  |  |  | 76 | 310502800-031-G |  | IC,Buffer,74LVC1G07GW,1.65~5.5V,G,SOT353-5,SMD | NXP SEMICONDUCTORS | 74LVC1G07GW | 1 |  | U103 |
|  |  |  |  | 77 | 62012A400-015-G |  | CAP,100nF,+/-10%,X7R,25V,G,SMD0402 | MURATA ELEC. NORTH AMERICA | GRM155R71E104KE14D | 1 |  | C2097 |
|  |  |  |  | 78 | 610107A00-017-G |  | RES,0 Ohm,+/-5%,1/16W,G,SMD0402 | KOA SPEER ELECTRONICS, INC. | RK73Z1ETTP | 1 |  | R1445 |
|  |  |  |  | 79 | 61010L300-017-G |  | RES,1KOhm,+/-1%,1/16W,G,SMD0402 | KOA SPEER ELECTRONICS, INC. | RK73H1ETTP1001F | 1 |  | R1444,R1016,R1022, |
|  |  |  |  | 80 | 620106200-015-G |  | CAP,10nF,+/-10%,X7R,16V,G,SMD0402 | MURATA ELEC. NORTH AMERICA | GRM155R71C103KA01D | 1 |  | C2098 |
|  |  |  |  | 81 | 320403K00-183-G |  | IC,Temp Sensor,TMP75AIDR,3°C,G,SOIC-8,SMD | TEXAS INSTRUMENTS | TMP75AIDR | 1 |  | U_TMP |
|  |  |  |  | 82 | 340653G00-317-G |  | CONN,Header,Shrouded,2X11,V/T,Bla,2mm,30u,G,SMD-22 | MOLEX INCORPORATED | 87832-6023 | 1 |  | J102 |
|  |  |  |  | 83 | 3406ALY00-317-G |  | CONN,Header,Shrouded,2X6,V/T,Bla,2mm,30u,G,SMD-12 | MOLEX INCORPORATED | 87832-5523 | 1 |  | J103 |
|  |  |  |  | 84 | 310504D00-031-G |  | IC,Buffer,74LVC2G125DP,1.65~5.5V,G,TSSOP-8,SMD | NXP SEMICONDUCTORS | 74LVC2G125DP | 1 |  | U31 |
|  |  |  |  | 85 | 510301N00-223-G |  | MOS N,2N7002LT1G,60V,0.115A,7.5ohm@5V,G,SOT23-3,SMD | ON SEMICONDUCTOR CORP | 2N7002LT1G | 2 |  | Q3,Q4 |
|  |  |  |  | 86 | 730200800-101-G |  | Polyswitch,PTC,6V,1.5A,G,SMD1206 | BOURNS INC | MF-NSMF150-2 | 1 |  | FS1 |
|  |  |  |  | 87 | 630100U00-016-G |  | IND,68nH@50MHz,+/-20%,50mA,300mOhm,G,SMD0603 | TDK ELECTRONICS EUROPE GMBH | MLF1608D68NMT | 3 |  | L18,L19,L20 |
|  |  |  |  | 88 | 720107U00-015-G |  | FB,220 Ohm@100MHz,+/-25%,2A,50mOhm,G,SMD0805 | MURATA ELEC. NORTH AMERICA | BLM21PG221SN1D | 1 |  | L21 |
|  |  |  |  | 89 | 520300500-223-G |  | DIODE,Schottky,BAT54SLT1G,30V,0.2A,G,SOT23-3,SMD | ON SEMICONDUCTOR CORP | BAT54SLT1G | 7 |  | D9,D10,D11,D12,D13,D16,D18 |
|  |  |  |  | 90 | 520305J00-223-G |  | DIODE,Schottky,MBR130LSFT1G,30V,1A,G,SOD123FL-2,SMD | ON SEMICONDUCTOR CORP | MBR130LSFT1G | 1 |  | D14 |
|  |  |  |  | 91 | 520306Y00-223-G |  | DIODE,Schottky Rectifier,MBR0530T1G,30V,0.5A,G,SOD123-2,SMD | ON SEMICONDUCTOR CORP | MBR0530T1G | 2 |  | D15,D17 |
|  |  |  |  | 92 | 61010FF00-017-G |  | RES,150 Ohm,+/-1%,1/16W,G,SMD0402 | KOA SPEER ELECTRONICS, INC. | RK73H1ETTP1500F | 6 |  | R1006,R1007,R1008,R1009,R1010,R1011 |
|  |  |  |  | 93 | 61010LA00-017-G |  | RES,4.7KOhm,+/-1%,1/16W,G,SMD0402 | KOA SPEER ELECTRONICS, INC. | RK73H1ETTP4701F | 2 |  | R1017,R1023 |
|  |  |  |  | 94 | 61011DR00-017-G |  | RES,2.2KOhm,+/-1%,1/16W,G,SMD0402 | KOA SPEER ELECTRONICS, INC. | RK73H1ETTP2201F | 2 |  | R1018,R1024 |
|  |  |  |  | 95 | 610115J00-017-G |  | RES,33 Ohm,+/-1%,1/16W,G,SMD0402 | KOA SPEER ELECTRONICS, INC. | RK73H1ETTP33R0F | 2 |  | R1019,R1025 |
|  |  |  |  | 96 | 62010K200-015-G |  | CAP,12pF,+/-5%,NPO(C0G),50V,G,SMD0402 | MURATA ELEC. NORTH AMERICA | GRM1555C1H120J | 6 |  | C1546,C1547,C1548,C1549,C1550,C1551 |
|  |  |  |  | 97 | 620101T02-015-G |  | CAP,100nF,+/-10%,X7R,16V,G,SMD0402 | MURATA ELEC. NORTH AMERICA | GRM155R71C104K | 3 |  | C1552,C1561,C1562 |
|  |  |  |  | 98 | 620108000-015-G |  | CAP,100pF,+/-5%,NPO(C0G),50V,G,SMD0402 | MURATA ELEC. NORTH AMERICA | GRM1555C1H101J | 4 |  | C1554,C1559,C1565,C1567 |
|  |  |  |  | 99 | 62010GW00-015-G |  | CAP,10pF,+/-5%,NPO,50V,G,SMD0402 | MURATA ELEC. NORTH AMERICA | GRM1555C1H100J | 4 |  | C1555,C1560,C1564,C1566 |
|  |  |  |  | 100 | 62011D900-015-G |  | CAP,22uF,+/-10%,X7R,6.3V,G,SMD1206 | MURATA ELEC. NORTH AMERICA | GRM31CR70J226K | 1 |  | C1563 |
